# S9S_MB_2U (Grand Teton) — schematic netlist excerpt (pin names and nets, part order shuffled) for the footprints in the layout excerpt that follows; sources: Cadence DE-HDL packaged netlist, KiCad conversion of 03242023_DA0F0TMBIJ0_F0T_Motherboard_J_brd_V01_OCP.brd

PU23_P1_8  ISL99390FRZTR5935  ISL99390FRZ-TR5935 IC  pkg QFN21_6X5XB  page 288
  VOS  = PVCCIN_CPU1_VOS8
  AGND  = GND
  VCC  = PVCCIN_CPU1_VDD8
  PVCC  = PVCCIN_CPU1_PVCC
  PGND1  = GND
  GL1  = NC
  PGND2  = GND
  SW  = SW_PVCCIN_CPU1_SW8
  VIN1  = SW_P12V_PVCCIN_CPU1_FLT
  VIN2  = SW_P12V_PVCCIN_CPU1_FLT
  DNC  = NC
  PHASE  = SW_PVCCIN_CPU1_BOOTR8
  BOOT  = SW_PVCCIN_CPU1_BOOT8
  PWM  = PVCCIN_CPU1_PWM8
  EN  = PVCCIN_CPU1_VDD8
  TOUT_FLT  = PVCCIN_CPU1_ATSEN
  LSET  = PVCCIN_CPU1_LSET8
  IOUT  = PVCCIN_CPU1_IMON8
  REFIN  = PVCCIN_CPU1_VREF
  PGND3  = GND
  GL2  = NC

(kicad_pcb
	(version 20260206)
	(generator "pcbnew")
	(generator_version "10.0")
	(general
		(thickness 1.6)
		(legacy_teardrops no)
	)
	(paper "A4")
	(title_block
		(title "03242023_DA0F0TMBIJ0_F0T_Motherboard_J_brd_V01_OCP.brd")
		(comment 1 "Grand Teton / footprints 2683-2683 of 6105")
	)
	(layers
		(0 "F.Cu" signal "TOP")
		(4 "In1.Cu" signal "GND")
		(6 "In2.Cu" signal "IN1")
		(8 "In3.Cu" signal "GND1")
		(10 "In4.Cu" signal "IN2")
		(12 "In5.Cu" signal "GND2")
		(14 "In6.Cu" signal "IN3")
		(16 "In7.Cu" signal "GND3")
		(18 "In8.Cu" signal "VCC")
		(20 "In9.Cu" signal "VCC1")
		(22 "In10.Cu" signal "GND4")
		(24 "In11.Cu" signal "IN4")
		(26 "In12.Cu" signal "GND5")
		(28 "In13.Cu" signal "IN5")
		(30 "In14.Cu" signal "GND6")
		(32 "In15.Cu" signal "IN6")
		(34 "In16.Cu" signal "GND7")
		(2 "B.Cu" signal "BOTTOM")
		(9 "F.Adhes" user "F.Adhesive")
		(11 "B.Adhes" user "B.Adhesive")
		(13 "F.Paste" user "Package Geometry/Pastemask Top")
		(15 "B.Paste" user "Package Geometry/Pastemask Bottom")
		(5 "F.SilkS" user "Ref Des/Silkscreen Top")
		(7 "B.SilkS" user "Ref Des/Silkscreen Bottom")
		(1 "F.Mask" user "Board Geometry/Soldermask Top")
		(3 "B.Mask" user "Board Geometry/Soldermask Bottom")
		(17 "Dwgs.User" user "User.Drawings")
		(19 "Cmts.User" user "User.Comments")
		(21 "Eco1.User" user "User.Eco1")
		(23 "Eco2.User" user "User.Eco2")
		(25 "Edge.Cuts" user "Board Geometry/Outline")
		(27 "Margin" user)
		(31 "F.CrtYd" user "Package Geometry/Place Bound Top")
		(29 "B.CrtYd" user "Package Geometry/Place Bound Bottom")
		(35 "F.Fab" user "Ref Des/Assembly Top")
		(33 "B.Fab" user "Ref Des/Assembly Bottom")
	)
	(footprint ""
		(layer "F.Cu")
		(at 137.800334 -342.917018)
		(property "Reference" "PU23_P1_8"
			(at 0.53848 -6.47827 0)
			(unlocked yes)
			(layer "F.SilkS")
			(effects
				(font
					(size 0.7874 0.5842)
					(thickness 0.1524)
				)
				(justify left)
			)
		)
		(property "Value" ""
			(at 0 0 0)
			(layer "F.Fab")
			(effects
				(font
					(size 1.27 1.27)
				)
			)
		)
		(duplicate_pad_numbers_are_jumpers no)
		(fp_line
			(start -2.500122 -2.999994)
			(end -2.24409 -2.999994)
			(stroke
				(width 0.1524)
				(type default)
			)
			(layer "F.SilkS")
		)
		(fp_line
			(start -2.500122 -2.529078)
			(end -2.500122 -2.999994)
			(stroke
				(width 0.1524)
				(type default)
			)
			(layer "F.SilkS")
		)
		(fp_line
			(start -2.500122 0.6604)
			(end -2.500122 0.229108)
			(stroke
				(width 0.1524)
				(type default)
			)
			(layer "F.SilkS")
		)
		(fp_line
			(start -2.500122 2.999994)
			(end -2.500122 2.339594)
			(stroke
				(width 0.1524)
				(type default)
			)
			(layer "F.SilkS")
		)
		(fp_line
			(start -2.2987 2.999994)
			(end -2.500122 2.999994)
			(stroke
				(width 0.1524)
				(type default)
			)
			(layer "F.SilkS")
		)
		(fp_line
			(start 2.31394 -2.999994)
			(end 2.500122 -2.999994)
			(stroke
				(width 0.1524)
				(type default)
			)
			(layer "F.SilkS")
		)
		(fp_line
			(start 2.500122 -2.999994)
			(end 2.500122 -2.44348)
			(stroke
				(width 0.1524)
				(type default)
			)
			(layer "F.SilkS")
		)
		(fp_line
			(start 2.500122 2.339594)
			(end 2.500122 2.999994)
			(stroke
				(width 0.1524)
				(type default)
			)
			(layer "F.SilkS")
		)
		(fp_line
			(start 2.500122 2.999994)
			(end 2.2987 2.999994)
			(stroke
				(width 0.1524)
				(type default)
			)
			(layer "F.SilkS")
		)
		(fp_poly
			(pts
				(xy -2.234946 -3.650488) (xy -2.742946 -2.634488) (xy -3.250946 -3.650488)
			)
			(stroke
				(width 0)
				(type default)
			)
			(fill yes)
			(layer "F.SilkS")
		)
		(fp_line
			(start -2.500122 -2.999994)
			(end 2.500122 -2.999994)
			(stroke
				(width 0.1)
				(type default)
			)
			(layer "F.Fab")
		)
		(fp_line
			(start -2.500122 2.999994)
			(end -2.500122 -2.999994)
			(stroke
				(width 0.1)
				(type default)
			)
			(layer "F.Fab")
		)
		(fp_line
			(start 2.500122 -2.999994)
			(end 2.500122 2.999994)
			(stroke
				(width 0.1)
				(type default)
			)
			(layer "F.Fab")
		)
		(fp_line
			(start 2.500122 2.999994)
			(end -2.500122 2.999994)
			(stroke
				(width 0.1)
				(type default)
			)
			(layer "F.Fab")
		)
		(fp_poly
			(pts
				(xy -4.218432 -2.783078) (xy -4.218432 -1.767078) (xy -3.202432 -2.275078)
			)
			(stroke
				(width 0)
				(type default)
			)
			(fill yes)
			(layer "F.Fab")
		)
		(pad "1" smd rect
			(at -2.400046 -2.275078 90)
			(size 0.2286 0.6096)
			(layers "F.Cu" "F.Mask" "F.Paste")
			(net "PVCCIN_CPU1_VOS8")
		)
		(pad "2" smd rect
			(at -2.400046 -1.82499 90)
			(size 0.2286 0.6096)
			(layers "F.Cu" "F.Mask" "F.Paste")
			(net "GND")
		)
		(pad "3" smd rect
			(at -2.400046 -1.374902 90)
			(size 0.2286 0.6096)
			(layers "F.Cu" "F.Mask" "F.Paste")
			(net "PVCCIN_CPU1_VDD8")
		)
		(pad "4" smd rect
			(at -2.400046 -0.925068 90)
			(size 0.2286 0.6096)
			(layers "F.Cu" "F.Mask" "F.Paste")
			(net "PVCCIN_CPU1_PVCC")
		)
		(pad "5" smd rect
			(at -2.400046 -0.47498 90)
			(size 0.2286 0.6096)
			(layers "F.Cu" "F.Mask" "F.Paste")
			(net "GND")
		)
		(pad "6" smd rect
			(at -2.400046 -0.024892 90)
			(size 0.2286 0.6096)
			(layers "F.Cu" "F.Mask" "F.Paste")
			(net "Net_8541")
		)
		(pad "7_9-20_24" smd circle
			(at 0 1.150112 90)
			(size 0 0)
			(layers "F.Cu" "F.Mask" "F.Paste")
			(net "GND")
		)
		(pad "10_19" smd rect
			(at 0 2.899918 90)
			(size 0.6096 4.318)
			(layers "F.Cu" "F.Mask" "F.Paste")
			(net "SW_PVCCIN_CPU1_SW8")
		)
		(pad "25_29" smd rect
			(at 1.549908 -1.279906 270)
			(size 2.0574 2.3114)
			(layers "F.Cu" "F.Mask" "F.Paste")
			(net "SW_P12V_PVCCIN_CPU1_FLT")
		)
		(pad "30" smd rect
			(at 2.05994 -2.899918)
			(size 0.2286 0.6096)
			(layers "F.Cu" "F.Mask" "F.Paste")
			(net "SW_P12V_PVCCIN_CPU1_FLT")
		)
		(pad "31" smd rect
			(at 1.610106 -2.899918)
			(size 0.2286 0.6096)
			(layers "F.Cu" "F.Mask" "F.Paste")
			(net "Net_8542")
		)
		(pad "32" smd rect
			(at 1.160018 -2.899918)
			(size 0.2286 0.6096)
			(layers "F.Cu" "F.Mask" "F.Paste")
			(net "SW_PVCCIN_CPU1_BOOTR8")
		)
		(pad "33" smd rect
			(at 0.70993 -2.899918)
			(size 0.2286 0.6096)
			(layers "F.Cu" "F.Mask" "F.Paste")
			(net "SW_PVCCIN_CPU1_BOOT8")
		)
		(pad "34" smd rect
			(at 0.260096 -2.899918)
			(size 0.2286 0.6096)
			(layers "F.Cu" "F.Mask" "F.Paste")
			(net "PVCCIN_CPU1_PWM8")
		)
		(pad "35" smd rect
			(at -0.189992 -2.899918)
			(size 0.2286 0.6096)
			(layers "F.Cu" "F.Mask" "F.Paste")
			(net "PVCCIN_CPU1_VDD8")
		)
		(pad "36" smd rect
			(at -0.64008 -2.899918)
			(size 0.2286 0.6096)
			(layers "F.Cu" "F.Mask" "F.Paste")
			(net "PVCCIN_CPU1_ATSEN")
		)
		(pad "37" smd rect
			(at -1.089914 -2.899918)
			(size 0.2286 0.6096)
			(layers "F.Cu" "F.Mask" "F.Paste")
			(net "PVCCIN_CPU1_LSET8")
		)
		(pad "38" smd rect
			(at -1.540002 -2.899918)
			(size 0.2286 0.6096)
			(layers "F.Cu" "F.Mask" "F.Paste")
			(net "PVCCIN_CPU1_IMON8")
		)
		(pad "39" smd rect
			(at -1.99009 -2.899918)
			(size 0.2286 0.6096)
			(layers "F.Cu" "F.Mask" "F.Paste")
			(net "PVCCIN_CPU1_VREF")
		)
		(pad "40" smd rect
			(at -0.87503 -1.27508)
			(size 1.7526 1.9558)
			(layers "F.Cu" "F.Mask" "F.Paste")
			(net "GND")
		)
		(pad "41" smd rect
			(at -1.525016 0.249936 270)
			(size 0.3048 0.4572)
			(layers "F.Cu" "F.Mask" "F.Paste")
			(net "Net_8540")
		)
		(zone
			(layer "F.Cu")
			(hatch none 0.5)
			(connect_pads
				(clearance 0)
			)
			(min_thickness 0.25)
			(keepout
				(tracks not_allowed)
				(vias allowed)
				(pads allowed)
				(copperpour not_allowed)
				(footprints allowed)
			)
			(placement
				(enabled no)
				(sheetname "")
			)
			(fill
				(thermal_gap 0.5)
				(thermal_bridge_width 0.5)
				(island_removal_mode 0)
			)
			(polygon
				(pts
					(xy 135.300212 -339.917024) (xy 135.300212 -340.666324) (xy 140.300456 -340.666324) (xy 140.300456 -339.917024)
					(xy 140.010134 -339.917024) (xy 140.010134 -340.3727) (xy 135.590534 -340.3727) (xy 135.590534 -339.917024)
				)
			)
		)
		(zone
			(layer "F.Cu")
			(hatch none 0.5)
			(connect_pads
				(clearance 0)
			)
			(min_thickness 0.25)
			(keepout
				(tracks not_allowed)
				(vias allowed)
				(pads allowed)
				(copperpour not_allowed)
				(footprints allowed)
			)
			(placement
				(enabled no)
				(sheetname "")
			)
			(fill
				(thermal_gap 0.5)
				(thermal_bridge_width 0.5)
				(island_removal_mode 0)
			)
			(polygon
				(pts
					(xy 135.755888 -343.233248) (xy 135.998204 -343.233248) (xy 135.998204 -343.163398) (xy 136.78662 -343.163398)
					(xy 136.78662 -342.854788) (xy 136.849612 -342.854788) (xy 136.849612 -342.167718) (xy 135.300212 -342.167718)
					(xy 135.300212 -342.62441) (xy 135.995918 -342.62441) (xy 135.995918 -342.463882) (xy 136.554718 -342.463882)
					(xy 136.554718 -342.870282) (xy 135.995918 -342.870282) (xy 135.995918 -342.64981) (xy 135.300212 -342.64981)
					(xy 135.300212 -342.77681) (xy 135.755888 -342.77681)
				)
			)
		)
	)
)
